(kicad_pcb
	(version 20260206)
	(generator "pcbnew")
	(generator_version "10.0")
	(general
		(thickness 1.59074)
		(legacy_teardrops no)
	)
	(paper "A4")
	(title_block
		(title "osc-sa45 — FAB_SA45_DaughterCard.PcbDoc")
		(comment 1 "Time Appliance Project (Time Card) / footprints 31-38 of 44")
	)
	(layers
		(0 "F.Cu" signal "L01-Top Layer")
		(4 "In1.Cu" signal "L02-Inner Layer")
		(6 "In2.Cu" signal "L03-Inner Layer")
		(2 "B.Cu" signal "L04-Bottom Layer")
		(9 "F.Adhes" user "F.Adhesive")
		(11 "B.Adhes" user "B.Adhesive")
		(13 "F.Paste" user "Top Paste")
		(15 "B.Paste" user "Bottom Paste")
		(5 "F.SilkS" user "Top Overlay")
		(7 "B.SilkS" user "Bottom Overlay")
		(1 "F.Mask" user "Top Solder")
		(3 "B.Mask" user "Bottom Solder")
		(17 "Dwgs.User" user "User.Drawings")
		(19 "Cmts.User" user "User.Comments")
		(21 "Eco1.User" user "User.Eco1")
		(23 "Eco2.User" user "User.Eco2")
		(25 "Edge.Cuts" user)
		(27 "Margin" user)
		(31 "F.CrtYd" user "Top Courtyard")
		(29 "B.CrtYd" user "Bottom Courtyard")
		(35 "F.Fab" user "Top Component Outline")
		(33 "B.Fab" user "Bottom Component Outline 2")
	)
	(footprint "FAB_SA45_DaughterCard:Keystone_4871"
		(locked yes)
		(layer "B.Cu")
		(at 163.661105 126.343605 180)
		(property "Reference" "J4"
			(at -0.00185 4.4071 0)
			(unlocked yes)
			(layer "B.SilkS")
			(effects
				(font
					(face "Arial")
					(size 0.63 0.63)
					(thickness 0.254)
				)
				(justify mirror)
			)
		)
		(property "Value" "Keystone_4871"
			(at 6.3343 -5.019802 0)
			(unlocked yes)
			(layer "B.SilkS")
			(hide yes)
			(effects
				(font
					(size 1.524 1.524)
					(thickness 0.254)
				)
				(justify mirror)
			)
		)
		(sheetname "SCH_SA45_DaughterCard")
		(sheetfile "SCH_SA45_DaughterCard.kicad_sch")
		(duplicate_pad_numbers_are_jumpers no)
		(fp_line
			(start 3.4 3.4)
			(end -3.4 3.4)
			(stroke
				(width 0.1)
				(type solid)
			)
			(layer "B.CrtYd")
		)
		(fp_line
			(start 3.4 -3.4)
			(end 3.4 3.4)
			(stroke
				(width 0.1)
				(type solid)
			)
			(layer "B.CrtYd")
		)
		(fp_line
			(start 3.4 -3.4)
			(end -3.4 -3.4)
			(stroke
				(width 0.1)
				(type solid)
			)
			(layer "B.CrtYd")
		)
		(fp_line
			(start -3.4 -0.8)
			(end -3.4 3.4)
			(stroke
				(width 0.1)
				(type solid)
			)
			(layer "B.CrtYd")
		)
		(fp_line
			(start -3.4 -3.4)
			(end -3.4 -0.8)
			(stroke
				(width 0.1)
				(type solid)
			)
			(layer "B.CrtYd")
		)
		(fp_text user ""
			(at 0.367795 0.63446 360)
			(unlocked yes)
			(layer "B.Fab")
			(effects
				(font
					(face "Arial")
					(size 0.63 0.63)
					(thickness 0.254)
				)
				(justify mirror)
			)
		)
		(fp_text user "${REFERENCE}"
			(at -0.00185 0.20085 360)
			(unlocked yes)
			(layer "B.Fab")
			(effects
				(font
					(face "Arial")
					(size 0.63 0.63)
					(thickness 0.254)
				)
				(justify mirror)
			)
		)
		(pad "Hole" thru_hole circle
			(at 0 0 180)
			(size 0 0)
			(drill 3.7)
			(layers "*.Cu" "*.Mask")
			(remove_unused_layers no)
			(thermal_bridge_angle 90)
		)
		(pad "MT" smd circle
			(at 0 0 180)
			(size 6.2 6.2)
			(layers "B.Cu" "B.Mask" "B.Paste")
			(solder_mask_margin 0.05)
			(thermal_bridge_angle 90)
		)
	)
	(footprint "Vault:TH001V_109DIA_000mt_8600-0"
		(layer "B.Cu")
		(at 139.383105 81.993605 180)
		(property "Reference" "P9"
			(at 0 -1.90429 0)
			(unlocked yes)
			(layer "B.SilkS")
			(effects
				(font
					(face "Arial")
					(size 0.63 0.63)
					(thickness 0.254)
				)
				(justify mirror)
			)
		)
		(property "Value" "Mill-Max_8600-0-05-80-00-00-03-0"
			(at 22.534825 -2.89778 0)
			(unlocked yes)
			(layer "B.SilkS")
			(hide yes)
			(effects
				(font
					(face "Arial")
					(size 0.63 0.63)
					(thickness 0.254)
				)
				(justify mirror)
			)
		)
		(sheetname "SCH_SA45_DaughterCard")
		(sheetfile "SCH_SA45_DaughterCard.kicad_sch")
		(duplicate_pad_numbers_are_jumpers no)
		(fp_line
			(start 1.4 1.4)
			(end -1.4 1.4)
			(stroke
				(width 0.1)
				(type solid)
			)
			(layer "B.CrtYd")
		)
		(fp_line
			(start 1.4 -1.4)
			(end 1.4 1.4)
			(stroke
				(width 0.1)
				(type solid)
			)
			(layer "B.CrtYd")
		)
		(fp_line
			(start 1.4 -1.4)
			(end -1.4 -1.4)
			(stroke
				(width 0.1)
				(type solid)
			)
			(layer "B.CrtYd")
		)
		(fp_line
			(start -1.4 -1.4)
			(end -1.4 1.4)
			(stroke
				(width 0.1)
				(type solid)
			)
			(layer "B.CrtYd")
		)
		(fp_circle
			(center 0 0)
			(end 0 0.545)
			(stroke
				(width 0.1)
				(type solid)
			)
			(fill no)
			(layer "B.Fab")
		)
		(fp_text user "${REFERENCE}"
			(at 0 0.166251 360)
			(unlocked yes)
			(layer "B.Fab")
			(effects
				(font
					(face "Arial")
					(size 0.8001 0.8001)
					(thickness 0.254)
				)
				(justify mirror)
			)
		)
		(pad "1" thru_hole circle
			(at 0 -0.02 180)
			(size 2.09 2.09)
			(drill 1.09)
			(layers "*.Cu" "*.Mask")
			(remove_unused_layers no)
			(net "1PPS_IN")
			(solder_mask_margin 0.05)
			(solder_paste_margin -2147.48364)
			(thermal_bridge_angle 90)
		)
	)
	(footprint "Vault:TH001V_109DIA_000mt_8600-0"
		(layer "B.Cu")
		(at 168.841105 84.663605 180)
		(property "Reference" "P3"
			(at -0.000005 2.21571 0)
			(unlocked yes)
			(layer "B.SilkS")
			(effects
				(font
					(face "Arial")
					(size 0.63 0.63)
					(thickness 0.254)
				)
				(justify mirror)
			)
		)
		(property "Value" "Mill-Max_8600-0-05-80-00-00-03-0"
			(at 22.534825 -2.89778 0)
			(unlocked yes)
			(layer "B.SilkS")
			(hide yes)
			(effects
				(font
					(face "Arial")
					(size 0.63 0.63)
					(thickness 0.254)
				)
				(justify mirror)
			)
		)
		(sheetname "SCH_SA45_DaughterCard")
		(sheetfile "SCH_SA45_DaughterCard.kicad_sch")
		(duplicate_pad_numbers_are_jumpers no)
		(fp_line
			(start 1.4 1.4)
			(end -1.4 1.4)
			(stroke
				(width 0.1)
				(type solid)
			)
			(layer "B.CrtYd")
		)
		(fp_line
			(start 1.4 -1.4)
			(end 1.4 1.4)
			(stroke
				(width 0.1)
				(type solid)
			)
			(layer "B.CrtYd")
		)
		(fp_line
			(start 1.4 -1.4)
			(end -1.4 -1.4)
			(stroke
				(width 0.1)
				(type solid)
			)
			(layer "B.CrtYd")
		)
		(fp_line
			(start -1.4 -1.4)
			(end -1.4 1.4)
			(stroke
				(width 0.1)
				(type solid)
			)
			(layer "B.CrtYd")
		)
		(fp_circle
			(center 0 0)
			(end 0 0.545)
			(stroke
				(width 0.1)
				(type solid)
			)
			(fill no)
			(layer "B.Fab")
		)
		(fp_text user "${REFERENCE}"
			(at 0 0.166251 360)
			(unlocked yes)
			(layer "B.Fab")
			(effects
				(font
					(face "Arial")
					(size 0.8001 0.8001)
					(thickness 0.254)
				)
				(justify mirror)
			)
		)
		(pad "1" thru_hole circle
			(at 0.04 -0.04 180)
			(size 2.09 2.09)
			(drill 1.09)
			(layers "*.Cu" "*.Mask")
			(remove_unused_layers no)
			(net "RF_OUTPUT")
			(solder_mask_margin 0.05)
			(solder_paste_margin -2147.48364)
			(thermal_bridge_angle 90)
		)
	)
	(footprint "Vault:CAPC1005X055N"
		(layer "B.Cu")
		(at 168.251105 117.243605 90)
		(property "Reference" "C2"
			(at 0.12655 1.449995 0)
			(unlocked yes)
			(layer "B.SilkS")
			(effects
				(font
					(face "Arial")
					(size 0.63 0.63)
					(thickness 0.254)
				)
				(justify mirror)
			)
		)
		(property "Value" "Murata_GRM155R61H104KE14D"
			(at -5.85071 -11.085985 0)
			(unlocked yes)
			(layer "B.SilkS")
			(hide yes)
			(effects
				(font
					(face "Arial")
					(size 0.63 0.63)
					(thickness 0.254)
				)
				(justify mirror)
			)
		)
		(sheetname "SCH_SA45_DaughterCard")
		(sheetfile "SCH_SA45_DaughterCard.kicad_sch")
		(duplicate_pad_numbers_are_jumpers no)
		(fp_line
			(start 0.95 -0.5)
			(end 0.95 0.5)
			(stroke
				(width 0.1)
				(type solid)
			)
			(layer "B.CrtYd")
		)
		(fp_line
			(start -0.95 -0.5)
			(end 0.95 -0.5)
			(stroke
				(width 0.1)
				(type solid)
			)
			(layer "B.CrtYd")
		)
		(fp_line
			(start -0.95 -0.5)
			(end -0.95 0.5)
			(stroke
				(width 0.1)
				(type solid)
			)
			(layer "B.CrtYd")
		)
		(fp_line
			(start -0.95 0.5)
			(end 0.95 0.5)
			(stroke
				(width 0.1)
				(type solid)
			)
			(layer "B.CrtYd")
		)
		(fp_line
			(start 0.5 -0.25)
			(end 0.5 0.25)
			(stroke
				(width 0.05)
				(type solid)
			)
			(layer "B.Fab")
		)
		(fp_line
			(start -0.5 -0.25)
			(end 0.5 -0.25)
			(stroke
				(width 0.05)
				(type solid)
			)
			(layer "B.Fab")
		)
		(fp_line
			(start -0.5 -0.25)
			(end -0.5 0.25)
			(stroke
				(width 0.05)
				(type solid)
			)
			(layer "B.Fab")
		)
		(fp_line
			(start -0.5 0.25)
			(end 0.5 0.25)
			(stroke
				(width 0.05)
				(type solid)
			)
			(layer "B.Fab")
		)
		(fp_text_box "${REFERENCE}"
			(start 1.14716 0.20757)
			(end -1.14714 -0.20756)
			(margins 0 0 0 0)
			(angle 180)
			(layer "B.Fab")
			(effects
				(font
					(face "Arial")
					(size 0.315 0.315)
					(thickness 0.254)
				)
				(justify top mirror)
			)
			(border no)
			(stroke
				(width 0.1)
				(type default)
			)
			(knockout no)
		)
		(pad "1" smd rect
			(at -0.46 0 90)
			(size 0.6 0.62)
			(layers "B.Cu" "B.Mask" "B.Paste")
			(net "+3.3V_OSC")
			(solder_mask_margin 0.05)
			(solder_paste_margin 0)
		)
		(pad "2" smd rect
			(at 0.46 0 90)
			(size 0.6 0.62)
			(layers "B.Cu" "B.Mask" "B.Paste")
			(net "GND")
			(solder_mask_margin 0.05)
			(solder_paste_margin 0)
		)
	)
	(footprint "Vault:FID_1p0mm"
		(layer "B.Cu")
		(at 171.276105 81.828605 180)
		(property "Reference" "Designator6"
			(at 7.084135 3.019298 0)
			(unlocked yes)
			(layer "B.SilkS")
			(hide yes)
			(effects
				(font
					(size 1.524 1.524)
					(thickness 0.254)
				)
				(justify mirror)
			)
		)
		(property "Value" "Comment"
			(at 5.07844 0.707898 0)
			(unlocked yes)
			(layer "B.SilkS")
			(hide yes)
			(effects
				(font
					(size 1.524 1.524)
					(thickness 0.254)
				)
				(justify mirror)
			)
		)
		(sheetfile ".kicad_sch")
		(duplicate_pad_numbers_are_jumpers no)
		(fp_circle
			(center 0 0)
			(end 0 1)
			(stroke
				(width 0.1)
				(type solid)
			)
			(fill no)
			(layer "B.CrtYd")
		)
		(pad "1" smd circle
			(at 0 0 90)
			(size 1 1)
			(layers "B.Cu" "B.Mask" "B.Paste")
			(solder_mask_margin 0.5)
			(solder_paste_margin -6)
			(thermal_bridge_angle 90)
		)
		(zone
			(layer "B.Cu")
			(hatch edge 0.5)
			(connect_pads
				(clearance 0)
			)
			(min_thickness 0.25)
			(keepout
				(tracks not_allowed)
				(vias not_allowed)
				(pads allowed)
				(copperpour not_allowed)
				(footprints allowed)
			)
			(placement
				(enabled no)
				(sheetname "")
			)
			(fill
				(thermal_gap 0.5)
				(thermal_bridge_width 0.5)
				(island_removal_mode 0)
			)
			(polygon
				(pts
					(xy 171.56639 80.871665) (xy 171.747502 80.946684) (xy 171.910498 81.055595) (xy 172.049115 81.194212)
					(xy 172.158026 81.357208) (xy 172.233045 81.53832) (xy 172.27129 81.730588) (xy 172.27129 81.926622)
					(xy 172.233045 82.11889) (xy 172.158026 82.300002) (xy 172.049115 82.462998) (xy 171.910498 82.601615)
					(xy 171.747502 82.710526) (xy 171.56639 82.785545) (xy 171.374122 82.82379) (xy 171.178088 82.82379)
					(xy 170.98582 82.785545) (xy 170.804708 82.710526) (xy 170.641712 82.601615) (xy 170.503095 82.462998)
					(xy 170.394184 82.300002) (xy 170.319165 82.11889) (xy 170.28092 81.926622) (xy 170.28092 81.762779)
					(xy 170.776105 81.762779) (xy 170.776105 81.894431) (xy 170.81018 82.021598) (xy 170.876006 82.135612)
					(xy 170.969098 82.228704) (xy 171.083112 82.29453) (xy 171.210279 82.328605) (xy 171.341931 82.328605)
					(xy 171.469098 82.29453) (xy 171.583112 82.228704) (xy 171.676204 82.135612) (xy 171.74203 82.021598)
					(xy 171.776105 81.894431) (xy 171.776105 81.762779) (xy 171.74203 81.635612) (xy 171.676204 81.521598)
					(xy 171.583112 81.428506) (xy 171.469098 81.36268) (xy 171.341931 81.328605) (xy 171.210279 81.328605)
					(xy 171.083112 81.36268) (xy 170.969098 81.428506) (xy 170.876006 81.521598) (xy 170.81018 81.635612)
					(xy 170.776105 81.762779) (xy 170.28092 81.762779) (xy 170.28092 81.730588) (xy 170.319165 81.53832)
					(xy 170.394184 81.357208) (xy 170.503095 81.194212) (xy 170.641712 81.055595) (xy 170.804708 80.946684)
					(xy 170.98582 80.871665) (xy 171.178088 80.83342) (xy 171.374122 80.83342)
				)
			)
		)
	)
	(footprint "Vault:CAPC2013X140N"
		(layer "B.Cu")
		(at 144.976105 117.953605)
		(property "Reference" "C8"
			(at -2.69615 -0.12655 0)
			(unlocked yes)
			(layer "B.SilkS")
			(effects
				(font
					(face "Arial")
					(size 0.63 0.63)
					(thickness 0.254)
				)
				(justify mirror)
			)
		)
		(property "Value" "Murata_GRM21BR61A226ME51L"
			(at -6.86959 -8.07786 0)
			(unlocked yes)
			(layer "B.SilkS")
			(hide yes)
			(effects
				(font
					(face "Arial")
					(size 0.63 0.63)
					(thickness 0.254)
				)
				(justify mirror)
			)
		)
		(sheetname "SCH_SA45_DaughterCard")
		(sheetfile "SCH_SA45_DaughterCard.kicad_sch")
		(duplicate_pad_numbers_are_jumpers no)
		(fp_line
			(start -1.8 -1.1)
			(end 1.8 -1.1)
			(stroke
				(width 0.1)
				(type solid)
			)
			(layer "B.CrtYd")
		)
		(fp_line
			(start -1.8 1.1)
			(end -1.8 -1.1)
			(stroke
				(width 0.1)
				(type solid)
			)
			(layer "B.CrtYd")
		)
		(fp_line
			(start -1.8 1.1)
			(end 1.8 1.1)
			(stroke
				(width 0.1)
				(type solid)
			)
			(layer "B.CrtYd")
		)
		(fp_line
			(start 1.8 1.1)
			(end 1.8 -1.1)
			(stroke
				(width 0.1)
				(type solid)
			)
			(layer "B.CrtYd")
		)
		(fp_line
			(start -1 -0.65)
			(end 1 -0.65)
			(stroke
				(width 0.05)
				(type solid)
			)
			(layer "B.Fab")
		)
		(fp_line
			(start -1 0.65)
			(end -1 -0.65)
			(stroke
				(width 0.05)
				(type solid)
			)
			(layer "B.Fab")
		)
		(fp_line
			(start -1 0.65)
			(end 1 0.65)
			(stroke
				(width 0.05)
				(type solid)
			)
			(layer "B.Fab")
		)
		(fp_line
			(start 1 0.65)
			(end 1 -0.65)
			(stroke
				(width 0.05)
				(type solid)
			)
			(layer "B.Fab")
		)
		(fp_text_box "${REFERENCE}"
			(start 1.09003 0.20729)
			(end -1.09005 -0.20729)
			(margins 0 0 0 0)
			(angle 180)
			(layer "B.Fab")
			(effects
				(font
					(face "Arial")
					(size 0.315 0.315)
					(thickness 0.254)
				)
				(justify top mirror)
			)
			(border no)
			(stroke
				(width 0.1)
				(type default)
			)
			(knockout no)
		)
		(pad "1" smd rect
			(at -0.9 0)
			(size 1.3 1.65)
			(layers "B.Cu" "B.Mask" "B.Paste")
			(net "+5V")
			(solder_mask_margin 0.05)
			(solder_paste_margin 0)
		)
		(pad "2" smd rect
			(at 0.9 0)
			(size 1.3 1.65)
			(layers "B.Cu" "B.Mask" "B.Paste")
			(net "GND")
			(solder_mask_margin 0.05)
			(solder_paste_margin 0)
		)
	)
	(footprint "Vault:RESC1608X55X30ML15T15"
		(layer "B.Cu")
		(at 167.951105 110.103605 90)
		(property "Reference" "R1"
			(at 0.85017 1.62893 0)
			(unlocked yes)
			(layer "B.SilkS")
			(effects
				(font
					(face "Arial")
					(size 0.63 0.63)
					(thickness 0.254)
				)
				(justify mirror)
			)
		)
		(property "Value" "100k"
			(at -1.74803 -0.353675 0)
			(unlocked yes)
			(layer "B.SilkS")
			(hide yes)
			(effects
				(font
					(face "Arial")
					(size 0.63 0.63)
					(thickness 0.254)
				)
				(justify mirror)
			)
		)
		(sheetname "SCH_SA45_DaughterCard")
		(sheetfile "SCH_SA45_DaughterCard.kicad_sch")
		(duplicate_pad_numbers_are_jumpers no)
		(fp_line
			(start 1.7 -1.05)
			(end 1.7 1.05)
			(stroke
				(width 0.05)
				(type solid)
			)
			(layer "B.CrtYd")
		)
		(fp_line
			(start -1.7 -1.05)
			(end 1.7 -1.05)
			(stroke
				(width 0.05)
				(type solid)
			)
			(layer "B.CrtYd")
		)
		(fp_line
			(start -1.7 -1.05)
			(end -1.7 1.05)
			(stroke
				(width 0.05)
				(type solid)
			)
			(layer "B.CrtYd")
		)
		(fp_line
			(start 0 -0.475)
			(end 0 0.475)
			(stroke
				(width 0.1)
				(type solid)
			)
			(layer "B.CrtYd")
		)
		(fp_line
			(start -0.475 0)
			(end 0.475 0)
			(stroke
				(width 0.1)
				(type solid)
			)
			(layer "B.CrtYd")
		)
		(fp_line
			(start -1.7 1.05)
			(end 1.7 1.05)
			(stroke
				(width 0.05)
				(type solid)
			)
			(layer "B.CrtYd")
		)
		(pad "1" smd rect
			(at -0.725 0)
			(size 1.05 0.9)
			(layers "B.Cu" "B.Mask" "B.Paste")
			(net "GND")
		)
		(pad "2" smd rect
			(at 0.725 0)
			(size 1.05 0.9)
			(layers "B.Cu" "B.Mask" "B.Paste")
			(net "1PPS_IN")
		)
	)
	(footprint "Vault:RESC1005X040N"
		(layer "B.Cu")
		(at 145.116105 104.648605 90)
		(property "Reference" "R5"
			(at 3.27165 -0.000005 0)
			(unlocked yes)
			(layer "B.SilkS")
			(effects
				(font
					(face "Arial")
					(size 0.63 0.63)
					(thickness 0.254)
				)
				(justify mirror)
			)
		)
		(property "Value" "Panasonic_ERJ-2RKF2702X"
			(at -11.07338 -15.610155 0)
			(unlocked yes)
			(layer "B.SilkS")
			(hide yes)
			(effects
				(font
					(face "Arial")
					(size 0.63 0.63)
					(thickness 0.254)
				)
				(justify mirror)
			)
		)
		(sheetname "SCH_SA45_DaughterCard")
		(sheetfile "SCH_SA45_DaughterCard.kicad_sch")
		(duplicate_pad_numbers_are_jumpers no)
		(fp_line
			(start 0.95 -0.5)
			(end 0.95 0.5)
			(stroke
				(width 0.1)
				(type solid)
			)
			(layer "B.CrtYd")
		)
		(fp_line
			(start -0.95 -0.5)
			(end 0.95 -0.5)
			(stroke
				(width 0.1)
				(type solid)
			)
			(layer "B.CrtYd")
		)
		(fp_line
			(start -0.95 -0.5)
			(end -0.95 0.5)
			(stroke
				(width 0.1)
				(type solid)
			)
			(layer "B.CrtYd")
		)
		(fp_line
			(start -0.95 0.5)
			(end 0.95 0.5)
			(stroke
				(width 0.1)
				(type solid)
			)
			(layer "B.CrtYd")
		)
		(fp_line
			(start 0.5 -0.25)
			(end 0.5 0.25)
			(stroke
				(width 0.05)
				(type solid)
			)
			(layer "B.Fab")
		)
		(fp_line
			(start -0.5 -0.25)
			(end 0.5 -0.25)
			(stroke
				(width 0.05)
				(type solid)
			)
			(layer "B.Fab")
		)
		(fp_line
			(start -0.5 -0.25)
			(end -0.5 0.25)
			(stroke
				(width 0.05)
				(type solid)
			)
			(layer "B.Fab")
		)
		(fp_line
			(start -0.5 0.25)
			(end 0.5 0.25)
			(stroke
				(width 0.05)
				(type solid)
			)
			(layer "B.Fab")
		)
		(fp_text_box "${REFERENCE}"
			(start 0.20727 -1.09004)
			(end -0.20726 1.09004)
			(margins 0 0 0 0)
			(angle -90)
			(layer "B.Fab")
			(effects
				(font
					(face "Arial")
					(size 0.315 0.315)
					(thickness 0.254)
				)
				(justify top mirror)
			)
			(border no)
			(stroke
				(width 0.1)
				(type default)
			)
			(knockout no)
		)
		(pad "1" smd rect
			(at -0.48 0 90)
			(size 0.57 0.62)
			(layers "B.Cu" "B.Mask" "B.Paste")
			(net "NetR5_1")
			(solder_mask_margin 0.05)
			(solder_paste_margin 0)
		)
		(pad "2" smd rect
			(at 0.48 0 90)
			(size 0.57 0.62)
			(layers "B.Cu" "B.Mask" "B.Paste")
			(net "NetC9_1")
			(solder_mask_margin 0.05)
			(solder_paste_margin 0)
		)
	)
)
